FILE_TYPE = CONNECTIVITY;
{Allegro Design Entry HDL 16.6-p007 (v16-6-112F) 10/10/2012}
"PAGE_NUMBER" = 169;
0"NC";
1"GND\g";
2"GND\g";
3"P5V_STBY\g";
4"P1V05_PCH_STBY\g"CDS_PHYS_NET_NAME"<<OCC_ONLY>>";
5"P3V3_STBY\g";
6"P12V_STBY\g";
7"GND\g";
8"P5V\g";
9"GND\g";
10"P3V3\g";
11"PVNN_PCH_STBY\g"CDS_PHYS_NET_NAME"<<OCC_ONLY>>";
12"GND\g";
13"GND\g";
14"P3V3_STBY\g";
15"P3V3_STBY\g";
16"GND\g";
17"GND\g";
18"GND\g";
19"GND\g";
20"A_P3V3_STBY_SCALED"CDS_PHYS_NET_NAME"<<OCC_ONLY>>"VOLTAGE"+1.8V";
21"A_P1V05_STBY_PCH_SENSOR"CDS_PHYS_NET_NAME"<<OCC_ONLY>>"VOLTAGE"+1.2V";
22"A_P5V_SCALED"VOLTAGE"+2V";
23"A_P5V_STBY_SCALED"CDS_PHYS_NET_NAME"<<OCC_ONLY>>"VOLTAGE"+2V";
24"A_P12V_STBY_SCALED"CDS_PHYS_NET_NAME"<<OCC_ONLY>>"VOLTAGE"+2V";
25"FM_BATTERY_SENSE_EN_N";
26"FM_BATTERY_SENSE_EN";
27"A_P3V3_SCALED"VOLTAGE"+2V";
28"A_PVNN_STBY_PCH_SENSOR"CDS_PHYS_NET_NAME"<<OCC_ONLY>>"VOLTAGE"+1.2V";
29"A_P3V_BAT_SCALED"CDS_PHYS_NET_NAME"<<OCC_ONLY>>"VOLTAGE"+1V";
30"P3V_BAT_SOURCE_R"VOLTAGE"+3V";
31"A_P3V_BAT_R";
%"RES"
"2","(400,2725)","0","mstr_discrete","I106";
;
CDS_SEC"1"
ROOM"BMC_VOLT_MONITOR"
CDS_LOCATION"R9G26"
SEC"1"
BOM_COST"SM_HM"
SEC_TYPE"0402"
CDS_LIB"mstr_discrete"
WATTAGE"1/16W"
MATERIAL"CHIP"
PACK_TYPE"0402"
TOLERANCE"1%"
VALUE"100.0K"
PART_NUMBER"G21796-010"
LOCATION"R9G26";
"A"
$PN"1"29;
"B"
$PN"2"1;
%"GND"
"1","(400,2500)","0","mstr_symbols","I107";
;
HDL_POWER"GND"
BODY_TYPE"PLUMBING"
SIZE"1B"
CDS_LIB"mstr_symbols"
VOLTAGE"0";
"A\NAC"1;
%"CAP"
"1","(800,2700)","0","mstr_discrete","I108";
;
CDS_SEC"1"
ROOM"BMC_VOLT_MONITOR"
CDS_LOCATION"C9G22"
SEC"1"
BOM_COST"SM_HM"
SEC_TYPE"0402LF"
CDS_LIB"mstr_discrete"
MATERIAL"COG"
VOLTAGE"50V"
PACK_TYPE"0402LF"
TOLERANCE"5%"
VALUE"10.0PF"
PART_NUMBER"A36094-025"
LOCATION"C9G22";
"A"
$PN"1"29;
"B"
$PN"2"2;
%"GND"
"1","(800,2500)","0","mstr_symbols","I109";
;
HDL_POWER"GND"
BODY_TYPE"PLUMBING"
SIZE"1B"
CDS_LIB"mstr_symbols"
VOLTAGE"0";
"A\NAC"2;
%"RES"
"2","(-4825,1425)","0","mstr_discrete","I114";
;
CDS_SEC"1"
ROOM"BMC_VOLT_MONITOR"
CDS_LOCATION"R1U38"
SEC"1"
BOM_COST"SM_HM"
CDS_LIB"mstr_discrete"
SEC_TYPE"0402"
WATTAGE"1/16W"
MATERIAL"CHIP"
PACK_TYPE"0402"
TOLERANCE"1%"
VALUE"8.2K"
PART_NUMBER"G21796-345"
LOCATION"R1U38";
"A"
$PN"1"20;
"B"
$PN"2"19;
%"RES"
"2","(-2850,1750)","0","mstr_discrete","I115";
;
CDS_SEC"1"
ROOM"BMC_VOLT_MONITOR"
CDS_LOCATION"R1U47"
SEC"1"
BOM_COST"SM_HM"
CDS_LIB"mstr_discrete"
SEC_TYPE"0402"
WATTAGE"1/16W"
MATERIAL"CHIP"
PACK_TYPE"0402"
TOLERANCE"1%"
VALUE"5.11K"
PART_NUMBER"G21796-140"
LOCATION"R1U47";
"A"
$PN"1"3;
"B"
$PN"2"23;
%"RES"
"2","(-2850,1350)","0","mstr_discrete","I116";
;
ROOM"BMC_VOLT_MONITOR"
CDS_LOCATION"R1U44"
$SEC"1"
CDS_SEC"1"
BOM_COST"SM_HM"
CDS_LIB"mstr_discrete"
WATTAGE"1/16W"
MATERIAL"CHIP"
PACK_TYPE"0402"
TOLERANCE"1.0%"
VALUE"3.48K"
PART_NUMBER"G21796-279"
LOCATION"R1U44";
"A"
$PN"1"23;
"B"
$PN"2"17;
%"P5V_STBY"
"1","(-2850,1975)","0","mstr_symbols","I119";
;
HDL_POWER"P5V_STBY"
BODY_TYPE"PLUMBING"
CDS_LIB"mstr_symbols"
SIZE"1B"
VOLTAGE"5.0V";
"G\NAC"3;
%"P1V05_PCH_STBY"
"1","(-4825,3775)","0","mstr_symbols","I121";
;
HDL_POWER"P1V05_PCH_STBY"
BODY_TYPE"PLUMBING"
CDS_LIB"mstr_symbols"
VOLTAGE"1.05V";
"G\NAC"4;
%"RES"
"2","(200,4025)","0","mstr_discrete","I126";
;
CDS_SEC"1"
ROOM"BMC_VOLT_MONITOR"
CDS_LOCATION"R1U50"
SEC"1"
BOM_COST"SM_HM"
SEC_TYPE"0402"
CDS_LIB"mstr_discrete"
WATTAGE"1/16W"
MATERIAL"CHIP"
PACK_TYPE"0402"
TOLERANCE"1%"
VALUE"200.0K"
PART_NUMBER"G21796-080"
LOCATION"R1U50";
"A"
$PN"1"31;
"B"
$PN"2"30;
%"P3V3_STBY"
"1","(-4825,2000)","0","mstr_symbols","I131";
;
HDL_POWER"P3V3_STBY"
BODY_TYPE"PLUMBING"
CDS_LIB"mstr_symbols"
SIZE"1B"
VOLTAGE"3.3V";
"G\NAC"5;
%"P12V_STBY"
"1","(-1125,2025)","0","mstr_symbols","I132";
;
HDL_POWER"P12V_STBY"
BODY_TYPE"PLUMBING"
CDS_LIB"mstr_symbols"
SIZE"1B"
VOLTAGE"12.0V";
"G\NAC"6;
%"CAP"
"1","(-4350,4550)","0","mstr_discrete","I139";
;
CDS_SEC"1"
ROOM"BMC_VOLT_MONITOR"
CDS_LOCATION"C9G15"
SEC"1"
BOM_COST"SM_HM"
CDS_LIB"mstr_discrete"
SEC_TYPE"0402LF"
MATERIAL"COG"
VOLTAGE"50V"
PACK_TYPE"0402LF"
TOLERANCE"5%"
VALUE"47.0PF"
PART_NUMBER"A36095-025"
LOCATION"C9G15";
"A"
$PN"1"22;
"B"
$PN"2"7;
%"RES"
"2","(-4700,4950)","0","mstr_discrete","I141";
;
CDS_SEC"1"
ROOM"BMC_VOLT_MONITOR"
CDS_LOCATION"R1U29"
SEC"1"
SEC_TYPE"0402"
CDS_LIB"mstr_discrete"
BOM_COST"SM_HM"
WATTAGE"1/16W"
MATERIAL"CHIP"
PACK_TYPE"0402"
TOLERANCE"1%"
VALUE"5.11K"
PART_NUMBER"G21796-140"
LOCATION"R1U29";
"A"
$PN"1"8;
"B"
$PN"2"22;
%"RES"
"2","(-4700,4550)","0","mstr_discrete","I142";
;
CDS_SEC"1"
ROOM"BMC_VOLT_MONITOR"
CDS_LOCATION"R1U28"
SEC"1"
SEC_TYPE"0402"
CDS_LIB"mstr_discrete"
BOM_COST"SM_HM"
WATTAGE"1/16W"
MATERIAL"CHIP"
PACK_TYPE"0402"
TOLERANCE"1.0%"
VALUE"3.48K"
PART_NUMBER"G21796-279"
LOCATION"R1U28";
"A"
$PN"1"22;
"B"
$PN"2"7;
%"GND"
"1","(-4700,4300)","0","mstr_symbols","I143";
;
HDL_POWER"GND"
BODY_TYPE"PLUMBING"
CDS_LIB"mstr_symbols"
SIZE"1B"
VOLTAGE"0";
"A\NAC"7;
%"P5V"
"1","(-4700,5175)","0","mstr_symbols","I144";
;
HDL_POWER"P5V"
BODY_TYPE"PLUMBING"
CDS_LIB"mstr_symbols"
SIZE"1B"
VOLTAGE"5.0V";
"G\NAC"8;
%"CAP"
"1","(-2550,4600)","0","mstr_discrete","I146";
;
CDS_SEC"1"
ROOM"BMC_VOLT_MONITOR"
CDS_LOCATION"C9G14"
SEC"1"
BOM_COST"SM_HM"
CDS_LIB"mstr_discrete"
SEC_TYPE"0402LF"
MATERIAL"COG"
VOLTAGE"50V"
PACK_TYPE"0402LF"
TOLERANCE"5%"
VALUE"47.0PF"
PART_NUMBER"A36095-025"
LOCATION"C9G14";
"A"
$PN"1"27;
"B"
$PN"2"9;
%"RES"
"2","(-2875,5000)","0","mstr_discrete","I148";
;
CDS_SEC"1"
ROOM"BMC_VOLT_MONITOR"
CDS_LOCATION"R1U26"
SEC"1"
SEC_TYPE"0402"
CDS_LIB"mstr_discrete"
BOM_COST"SM_HM"
WATTAGE"1/16W"
MATERIAL"CHIP"
PACK_TYPE"0402"
TOLERANCE"1%"
VALUE"5.11K"
PART_NUMBER"G21796-140"
LOCATION"R1U26";
"A"
$PN"1"10;
"B"
$PN"2"27;
%"RES"
"2","(-2875,4625)","0","mstr_discrete","I149";
;
CDS_SEC"1"
ROOM"BMC_VOLT_MONITOR"
CDS_LOCATION"R1U27"
SEC"1"
SEC_TYPE"0402"
CDS_LIB"mstr_discrete"
BOM_COST"SM_HM"
WATTAGE"1/16W"
MATERIAL"CHIP"
PACK_TYPE"0402"
TOLERANCE"1%"
VALUE"8.2K"
PART_NUMBER"G21796-345"
LOCATION"R1U27";
"A"
$PN"1"27;
"B"
$PN"2"9;
%"GND"
"1","(-2875,4350)","0","mstr_symbols","I150";
;
HDL_POWER"GND"
BODY_TYPE"PLUMBING"
CDS_LIB"mstr_symbols"
SIZE"1B"
VOLTAGE"0";
"A\NAC"9;
%"P3V3"
"1","(-2875,5200)","0","mstr_symbols","I151";
;
HDL_POWER"P3V3"
BODY_TYPE"PLUMBING"
CDS_LIB"mstr_symbols"
SIZE"1B"
VOLTAGE"3.3V";
"G\NAC"10;
%"CAP"
"1","(800,1475)","0","mstr_discrete","I153";
;
CDS_SEC"1"
ROOM"BMC_VOLT_MONITOR"
CDS_LOCATION"C9G18"
SEC"1"
BOM_COST"SM_HM"
CDS_LIB"mstr_discrete"
SEC_TYPE"0402LF"
MATERIAL"COG"
VOLTAGE"50V"
PACK_TYPE"0402LF"
TOLERANCE"5%"
VALUE"47.0PF"
PART_NUMBER"A36095-025"
LOCATION"C9G18";
"A"
$PN"1"28;
"B"
$PN"2"12;
%"PVNN_PCH_STBY"
"1","(800,2025)","0","mstr_symbols","I154";
;
HDL_POWER"PVNN_PCH_STBY"
BODY_TYPE"PLUMBING"
CDS_LIB"mstr_symbols"
VOLTAGE"1.0V";
"G\NAC"11;
%"FERRITE"
"4","(800,1850)","0","mstr_discrete","I155";
;
CDS_SEC"1"
ROOM"BMC_VOLT_MONITOR"
CDS_LOCATION"FB1U4"
SEC"1"
BOM_COST"SM_HM"
SEC_TYPE"SMLF"
CDS_LIB"mstr_discrete"
MATERIAL"FB"
PACK_TYPE"SMLF"
VALUE"30"
PART_NUMBER"693286-021"
LOCATION"FB1U4";
"A"
$PN"1"28;
"B"
$PN"2"11;
%"GND"
"1","(800,1250)","0","mstr_symbols","I156";
;
HDL_POWER"GND"
BODY_TYPE"PLUMBING"
SIZE"1B"
CDS_LIB"mstr_symbols"
VOLTAGE"0";
"A\NAC"12;
%"FET_N_DUAL"
"5","(200,3225)","0","mstr_discrete","I157";
;
CDS_SEC"2"
ROOM"BMC_VOLT_MONITOR"
CDS_LOCATION"Q9G1"
SEC"2"
CDS_LIB"mstr_discrete"
BOM_COST"SM_HM"
SEC_TYPE"SMLF"
PACK_TYPE"SMLF"
MATERIAL"FET"
VALUE"NTJD4001N"
PART_NUMBER"E40049-001"
LOCATION"Q9G1";
"GATE <SIZE -1..0>"
$PN"5"26;
"SOURCE <SIZE-1..0>"
$PN"4"29;
"DRAIN <SIZE -1..0>"
$PN"3"30;
%"GND"
"1","(-875,2525)","0","mstr_symbols","I160";
;
HDL_POWER"GND"
BODY_TYPE"PLUMBING"
CDS_LIB"mstr_symbols"
SIZE"1B"
VOLTAGE"0";
"A\NAC"13;
%"FET_N_DUAL"
"5","(-875,2900)","0","mstr_discrete","I162";
;
CDS_SEC"1"
ROOM"BMC_VOLT_MONITOR"
CDS_LOCATION"Q9G1"
SEC"1"
SEC_TYPE"SMLF"
BOM_COST"SM_HM"
CDS_LIB"mstr_discrete"
PACK_TYPE"SMLF"
MATERIAL"FET"
VALUE"NTJD4001N"
PART_NUMBER"E40049-001"
LOCATION"Q9G1";
"GATE <SIZE -1..0>"
$PN"2"25;
"SOURCE <SIZE-1..0>"
$PN"1"13;
"DRAIN <SIZE -1..0>"
$PN"6"26;
%"RES"
"2","(-650,3375)","0","mstr_discrete","I163";
;
CDS_SEC"1"
ROOM"BMC_VOLT_MONITOR"
CDS_LOCATION"R1U49"
SEC"1"
CDS_LIB"mstr_discrete"
BOM_COST"SM_HM"
SEC_TYPE"0402"
WATTAGE"1/16W"
MATERIAL"CHIP"
PACK_TYPE"0402"
TOLERANCE"1%"
VALUE"2.7K"
PART_NUMBER"G21796-344"
LOCATION"R1U49";
"A"
$PN"1"15;
"B"
$PN"2"26;
%"RES"
"2","(-1400,3025)","0","mstr_discrete","I164";
;
CDS_SEC"1"
CDS_LOCATION"R9G35"
SEC"1"
SEC_TYPE"0402"
CDS_LIB"mstr_discrete"
WATTAGE"1/16W"
MATERIAL"CHIP"
PACK_TYPE"0402"
TOLERANCE"1%"
VALUE"2.7K"
PART_NUMBER"G21796-344"
LOCATION"R9G35";
"A"
$PN"1"14;
"B"
$PN"2"25;
%"P3V3_STBY"
"1","(-1400,3325)","0","mstr_symbols","I165";
;
HDL_POWER"P3V3_STBY"
BODY_TYPE"PLUMBING"
CDS_LIB"mstr_symbols"
SIZE"1B"
VOLTAGE"3.3V";
"G\NAC"14;
%"P3V3_STBY"
"1","(-650,3600)","0","mstr_symbols","I166";
;
HDL_POWER"P3V3_STBY"
BODY_TYPE"PLUMBING"
CDS_LIB"mstr_symbols"
SIZE"1B"
VOLTAGE"3.3V";
"G\NAC"15;
%"CAP"
"1","(-4825,3250)","0","mstr_discrete","I56";
;
CDS_SEC"1"
ROOM"BMC_VOLT_MONITOR"
CDS_LOCATION"C1U21"
SEC"1"
BOM_COST"SM_HM"
CDS_LIB"mstr_discrete"
SEC_TYPE"0402LF"
MATERIAL"COG"
VOLTAGE"50V"
PACK_TYPE"0402LF"
TOLERANCE"5%"
VALUE"47.0PF"
PART_NUMBER"A36095-025"
LOCATION"C1U21";
"A"
$PN"1"21;
"B"
$PN"2"16;
%"FERRITE"
"4","(-4825,3600)","0","mstr_discrete","I57";
;
CDS_SEC"1"
ROOM"BMC_VOLT_MONITOR"
CDS_LOCATION"FB1U3"
SEC"1"
CDS_LIB"mstr_discrete"
SEC_TYPE"SMLF"
BOM_COST"SM_HM"
MATERIAL"FB"
PACK_TYPE"SMLF"
VALUE"30"
PART_NUMBER"693286-021"
LOCATION"FB1U3";
"A"
$PN"1"21;
"B"
$PN"2"4;
%"GND"
"1","(-4825,3000)","0","mstr_symbols","I58";
;
HDL_POWER"GND"
BODY_TYPE"PLUMBING"
CDS_LIB"mstr_symbols"
SIZE"1B"
VOLTAGE"0";
"A\NAC"16;
%"CAP"
"1","(-2500,1350)","0","mstr_discrete","I68";
;
CDS_SEC"1"
ROOM"BMC_VOLT_MONITOR"
CDS_LOCATION"C9G21"
SEC"1"
SEC_TYPE"0402LF"
CDS_LIB"mstr_discrete"
BOM_COST"SM_HM"
MATERIAL"COG"
VOLTAGE"50V"
PACK_TYPE"0402LF"
TOLERANCE"5%"
VALUE"47.0PF"
PART_NUMBER"A36095-025"
LOCATION"C9G21";
"A"
$PN"1"23;
"B"
$PN"2"17;
%"GND"
"1","(-2850,1100)","0","mstr_symbols","I71";
;
HDL_POWER"GND"
BODY_TYPE"PLUMBING"
CDS_LIB"mstr_symbols"
SIZE"1B"
VOLTAGE"0";
"A\NAC"17;
%"CAP"
"1","(-775,1450)","0","mstr_discrete","I80";
;
CDS_SEC"1"
ROOM"BMC_VOLT_MONITOR"
CDS_LOCATION"C9G17"
SEC"1"
SEC_TYPE"0402LF"
CDS_LIB"mstr_discrete"
BOM_COST"SM_HM"
MATERIAL"COG"
VOLTAGE"50V"
PACK_TYPE"0402LF"
TOLERANCE"5%"
VALUE"47.0PF"
PART_NUMBER"A36095-025"
LOCATION"C9G17";
"A"
$PN"1"24;
"B"
$PN"2"18;
%"RES"
"2","(-1125,1825)","0","mstr_discrete","I82";
;
CDS_SEC"1"
ROOM"BMC_VOLT_MONITOR"
CDS_LOCATION"R1U32"
SEC"1"
BOM_COST"SM_HM"
CDS_LIB"mstr_discrete"
SEC_TYPE"0402"
WATTAGE"1/16W"
MATERIAL"CHIP"
PACK_TYPE"0402"
TOLERANCE"1%"
VALUE"5.11K"
PART_NUMBER"G21796-140"
LOCATION"R1U32";
"A"
$PN"1"6;
"B"
$PN"2"24;
%"RES"
"2","(-1125,1450)","0","mstr_discrete","I83";
;
CDS_SEC"1"
ROOM"BMC_VOLT_MONITOR"
CDS_LOCATION"R1U33"
SEC"1"
BOM_COST"SM_HM"
CDS_LIB"mstr_discrete"
SEC_TYPE"0402"
WATTAGE"1/16W"
MATERIAL"CHIP"
PACK_TYPE"0402"
TOLERANCE"1%"
VALUE"1.00K"
PART_NUMBER"G21796-026"
LOCATION"R1U33";
"A"
$PN"1"24;
"B"
$PN"2"18;
%"GND"
"1","(-1125,1175)","0","mstr_symbols","I84";
;
HDL_POWER"GND"
BODY_TYPE"PLUMBING"
CDS_LIB"mstr_symbols"
SIZE"1B"
VOLTAGE"0";
"A\NAC"18;
%"CAP"
"1","(-4525,1425)","0","mstr_discrete","I86";
;
CDS_SEC"1"
ROOM"BMC_VOLT_MONITOR"
CDS_LOCATION"C9G20"
SEC"1"
SEC_TYPE"0402LF"
CDS_LIB"mstr_discrete"
BOM_COST"SM_HM"
MATERIAL"COG"
VOLTAGE"50V"
PACK_TYPE"0402LF"
TOLERANCE"5%"
VALUE"47.0PF"
PART_NUMBER"A36095-025"
LOCATION"C9G20";
"A"
$PN"1"20;
"B"
$PN"2"19;
%"RES"
"2","(-4825,1800)","0","mstr_discrete","I88";
;
CDS_SEC"1"
ROOM"BMC_VOLT_MONITOR"
CDS_LOCATION"R1U39"
SEC"1"
BOM_COST"SM_HM"
CDS_LIB"mstr_discrete"
SEC_TYPE"0402"
WATTAGE"1/16W"
MATERIAL"CHIP"
PACK_TYPE"0402"
TOLERANCE"1%"
VALUE"5.11K"
PART_NUMBER"G21796-140"
LOCATION"R1U39";
"A"
$PN"1"5;
"B"
$PN"2"20;
%"GND"
"1","(-4825,1150)","0","mstr_symbols","I90";
;
HDL_POWER"GND"
BODY_TYPE"PLUMBING"
CDS_LIB"mstr_symbols"
SIZE"1B"
VOLTAGE"0";
"A\NAC"19;
END.
